(kicad_pcb
	(version 20260206)
	(generator "pcbnew")
	(generator_version "10.0")
	(general
		(thickness 1.6)
		(legacy_teardrops no)
	)
	(paper "A4")
	(title_block
		(title "04192023_DAF0TMB3IC0_F0TG_MB_C_brd_V02_OCP.brd")
		(comment 1 "Grand Teton / footprints 5614-5620 of 8354")
	)
	(layers
		(0 "F.Cu" signal "TOP")
		(4 "In1.Cu" signal "GND")
		(6 "In2.Cu" signal "IN1")
		(8 "In3.Cu" signal "GND1")
		(10 "In4.Cu" signal "IN2")
		(12 "In5.Cu" signal "GND2")
		(14 "In6.Cu" signal "IN3")
		(16 "In7.Cu" signal "GND3")
		(18 "In8.Cu" signal "VCC")
		(20 "In9.Cu" signal "VCC1")
		(22 "In10.Cu" signal "GND4")
		(24 "In11.Cu" signal "IN4")
		(26 "In12.Cu" signal "GND5")
		(28 "In13.Cu" signal "IN5")
		(30 "In14.Cu" signal "GND6")
		(32 "In15.Cu" signal "IN6")
		(34 "In16.Cu" signal "GND7")
		(2 "B.Cu" signal "BOTTOM")
		(9 "F.Adhes" user "F.Adhesive")
		(11 "B.Adhes" user "B.Adhesive")
		(13 "F.Paste" user "Package Geometry/Pastemask Top")
		(15 "B.Paste" user "Package Geometry/Pastemask Bottom")
		(5 "F.SilkS" user "Ref Des/Silkscreen Top")
		(7 "B.SilkS" user "Ref Des/Silkscreen Bottom")
		(1 "F.Mask" user "Board Geometry/Soldermask Top")
		(3 "B.Mask" user "Board Geometry/Soldermask Bottom")
		(17 "Dwgs.User" user "User.Drawings")
		(19 "Cmts.User" user "User.Comments")
		(21 "Eco1.User" user "User.Eco1")
		(23 "Eco2.User" user "User.Eco2")
		(25 "Edge.Cuts" user "Board Geometry/Outline")
		(27 "Margin" user)
		(31 "F.CrtYd" user "Package Geometry/Place Bound Top")
		(29 "B.CrtYd" user "Package Geometry/Place Bound Bottom")
		(35 "F.Fab" user "Ref Des/Assembly Top")
		(33 "B.Fab" user "Ref Des/Assembly Bottom")
	)
	(footprint ""
		(layer "B.Cu")
		(at 200.406 -144.272 90)
		(property "Reference" "R8104"
			(at 0 0 90)
			(layer "B.SilkS")
			(hide yes)
			(effects
				(font
					(size 1.27 1.27)
				)
				(justify mirror)
			)
		)
		(property "Value" ""
			(at 0 0 90)
			(layer "B.Fab")
			(effects
				(font
					(size 1.27 1.27)
				)
				(justify mirror)
			)
		)
		(duplicate_pad_numbers_are_jumpers no)
		(fp_line
			(start 0.7874 -0.4064)
			(end -0.7874 -0.4064)
			(stroke
				(width 0.1524)
				(type default)
			)
			(layer "B.SilkS")
		)
		(fp_line
			(start -0.7874 -0.4064)
			(end -0.7874 0.4064)
			(stroke
				(width 0.1524)
				(type default)
			)
			(layer "B.SilkS")
		)
		(fp_line
			(start 0.7874 0.4064)
			(end 0.7874 -0.4064)
			(stroke
				(width 0.1524)
				(type default)
			)
			(layer "B.SilkS")
		)
		(fp_line
			(start -0.7874 0.4064)
			(end 0.7874 0.4064)
			(stroke
				(width 0.1524)
				(type default)
			)
			(layer "B.SilkS")
		)
		(fp_line
			(start 0.67945 -0.305054)
			(end 0.12065 -0.305054)
			(stroke
				(width 0.1)
				(type default)
			)
			(layer "B.Fab")
		)
		(fp_line
			(start 0.12065 -0.305054)
			(end 0.12065 -0.2794)
			(stroke
				(width 0.1)
				(type default)
			)
			(layer "B.Fab")
		)
		(fp_line
			(start -0.12065 -0.3048)
			(end -0.67945 -0.3048)
			(stroke
				(width 0.1)
				(type default)
			)
			(layer "B.Fab")
		)
		(fp_line
			(start -0.67945 -0.3048)
			(end -0.67945 0.3048)
			(stroke
				(width 0.1)
				(type default)
			)
			(layer "B.Fab")
		)
		(fp_line
			(start 0.12065 -0.2794)
			(end -0.12065 -0.2794)
			(stroke
				(width 0.1)
				(type default)
			)
			(layer "B.Fab")
		)
		(fp_line
			(start -0.12065 -0.2794)
			(end -0.12065 -0.3048)
			(stroke
				(width 0.1)
				(type default)
			)
			(layer "B.Fab")
		)
		(fp_line
			(start 0.12065 0.2794)
			(end 0.12065 0.3048)
			(stroke
				(width 0.1)
				(type default)
			)
			(layer "B.Fab")
		)
		(fp_line
			(start -0.120396 0.2794)
			(end 0.12065 0.2794)
			(stroke
				(width 0.1)
				(type default)
			)
			(layer "B.Fab")
		)
		(fp_line
			(start 0.67945 0.3048)
			(end 0.67945 -0.305054)
			(stroke
				(width 0.1)
				(type default)
			)
			(layer "B.Fab")
		)
		(fp_line
			(start 0.12065 0.3048)
			(end 0.67945 0.3048)
			(stroke
				(width 0.1)
				(type default)
			)
			(layer "B.Fab")
		)
		(fp_line
			(start -0.120396 0.3048)
			(end -0.120396 0.2794)
			(stroke
				(width 0.1)
				(type default)
			)
			(layer "B.Fab")
		)
		(fp_line
			(start -0.67945 0.3048)
			(end -0.120396 0.3048)
			(stroke
				(width 0.1)
				(type default)
			)
			(layer "B.Fab")
		)
		(pad "1" smd circle
			(at 0.40005 0 270)
			(size 0 0)
			(layers "B.Cu" "B.Mask" "B.Paste")
			(net "FM_AC_PWR_BTN_R_N")
		)
		(pad "2" smd circle
			(at -0.40005 0 270)
			(size 0 0)
			(layers "B.Cu" "B.Mask" "B.Paste")
			(net "FM_AC_PWR_BTN_PLD_N")
		)
	)
	(footprint ""
		(layer "B.Cu")
		(at 361.645454 -251.78131)
		(property "Reference" "C2536"
			(at 0 0 0)
			(layer "B.SilkS")
			(hide yes)
			(effects
				(font
					(size 1.27 1.27)
				)
				(justify mirror)
			)
		)
		(property "Value" ""
			(at 0 0 0)
			(layer "B.Fab")
			(effects
				(font
					(size 1.27 1.27)
				)
				(justify mirror)
			)
		)
		(duplicate_pad_numbers_are_jumpers no)
		(fp_line
			(start -0.7874 -0.4064)
			(end -0.7874 0.4064)
			(stroke
				(width 0.1524)
				(type default)
			)
			(layer "B.SilkS")
		)
		(fp_line
			(start -0.7874 0.4064)
			(end 0.7874 0.4064)
			(stroke
				(width 0.1524)
				(type default)
			)
			(layer "B.SilkS")
		)
		(fp_line
			(start 0.7874 -0.4064)
			(end -0.7874 -0.4064)
			(stroke
				(width 0.1524)
				(type default)
			)
			(layer "B.SilkS")
		)
		(fp_line
			(start 0.7874 0.4064)
			(end 0.7874 -0.4064)
			(stroke
				(width 0.1524)
				(type default)
			)
			(layer "B.SilkS")
		)
		(fp_line
			(start -0.67945 -0.3048)
			(end -0.67945 0.3048)
			(stroke
				(width 0.1)
				(type default)
			)
			(layer "B.Fab")
		)
		(fp_line
			(start -0.67945 0.3048)
			(end -0.120396 0.3048)
			(stroke
				(width 0.1)
				(type default)
			)
			(layer "B.Fab")
		)
		(fp_line
			(start -0.12065 -0.3048)
			(end -0.67945 -0.3048)
			(stroke
				(width 0.1)
				(type default)
			)
			(layer "B.Fab")
		)
		(fp_line
			(start -0.12065 -0.2794)
			(end -0.12065 -0.3048)
			(stroke
				(width 0.1)
				(type default)
			)
			(layer "B.Fab")
		)
		(fp_line
			(start -0.120396 0.2794)
			(end 0.12065 0.2794)
			(stroke
				(width 0.1)
				(type default)
			)
			(layer "B.Fab")
		)
		(fp_line
			(start -0.120396 0.3048)
			(end -0.120396 0.2794)
			(stroke
				(width 0.1)
				(type default)
			)
			(layer "B.Fab")
		)
		(fp_line
			(start 0.12065 -0.305054)
			(end 0.12065 -0.2794)
			(stroke
				(width 0.1)
				(type default)
			)
			(layer "B.Fab")
		)
		(fp_line
			(start 0.12065 -0.2794)
			(end -0.12065 -0.2794)
			(stroke
				(width 0.1)
				(type default)
			)
			(layer "B.Fab")
		)
		(fp_line
			(start 0.12065 0.2794)
			(end 0.12065 0.3048)
			(stroke
				(width 0.1)
				(type default)
			)
			(layer "B.Fab")
		)
		(fp_line
			(start 0.12065 0.3048)
			(end 0.67945 0.3048)
			(stroke
				(width 0.1)
				(type default)
			)
			(layer "B.Fab")
		)
		(fp_line
			(start 0.67945 -0.305054)
			(end 0.12065 -0.305054)
			(stroke
				(width 0.1)
				(type default)
			)
			(layer "B.Fab")
		)
		(fp_line
			(start 0.67945 0.3048)
			(end 0.67945 -0.305054)
			(stroke
				(width 0.1)
				(type default)
			)
			(layer "B.Fab")
		)
		(pad "1" smd circle
			(at 0.40005 0 180)
			(size 0 0)
			(layers "B.Cu" "B.Mask" "B.Paste")
			(net "PVDDCR_SOC_P0")
		)
		(pad "2" smd circle
			(at -0.40005 0 180)
			(size 0 0)
			(layers "B.Cu" "B.Mask" "B.Paste")
			(net "GND")
		)
	)
	(footprint ""
		(layer "B.Cu")
		(at 417.419028 -398.942052 90)
		(property "Reference" "C973"
			(at 0 0 90)
			(layer "B.SilkS")
			(hide yes)
			(effects
				(font
					(size 1.27 1.27)
				)
				(justify mirror)
			)
		)
		(property "Value" ""
			(at 0 0 90)
			(layer "B.Fab")
			(effects
				(font
					(size 1.27 1.27)
				)
				(justify mirror)
			)
		)
		(duplicate_pad_numbers_are_jumpers no)
		(fp_line
			(start 0.7874 -0.4064)
			(end -0.7874 -0.4064)
			(stroke
				(width 0.1524)
				(type default)
			)
			(layer "B.SilkS")
		)
		(fp_line
			(start -0.7874 -0.4064)
			(end -0.7874 0.4064)
			(stroke
				(width 0.1524)
				(type default)
			)
			(layer "B.SilkS")
		)
		(fp_line
			(start 0.7874 0.4064)
			(end 0.7874 -0.4064)
			(stroke
				(width 0.1524)
				(type default)
			)
			(layer "B.SilkS")
		)
		(fp_line
			(start -0.7874 0.4064)
			(end 0.7874 0.4064)
			(stroke
				(width 0.1524)
				(type default)
			)
			(layer "B.SilkS")
		)
		(fp_line
			(start 0.67945 -0.305054)
			(end 0.12065 -0.305054)
			(stroke
				(width 0.1)
				(type default)
			)
			(layer "B.Fab")
		)
		(fp_line
			(start 0.12065 -0.305054)
			(end 0.12065 -0.2794)
			(stroke
				(width 0.1)
				(type default)
			)
			(layer "B.Fab")
		)
		(fp_line
			(start -0.12065 -0.3048)
			(end -0.67945 -0.3048)
			(stroke
				(width 0.1)
				(type default)
			)
			(layer "B.Fab")
		)
		(fp_line
			(start -0.67945 -0.3048)
			(end -0.67945 0.3048)
			(stroke
				(width 0.1)
				(type default)
			)
			(layer "B.Fab")
		)
		(fp_line
			(start 0.12065 -0.2794)
			(end -0.12065 -0.2794)
			(stroke
				(width 0.1)
				(type default)
			)
			(layer "B.Fab")
		)
		(fp_line
			(start -0.12065 -0.2794)
			(end -0.12065 -0.3048)
			(stroke
				(width 0.1)
				(type default)
			)
			(layer "B.Fab")
		)
		(fp_line
			(start 0.12065 0.2794)
			(end 0.12065 0.3048)
			(stroke
				(width 0.1)
				(type default)
			)
			(layer "B.Fab")
		)
		(fp_line
			(start -0.120396 0.2794)
			(end 0.12065 0.2794)
			(stroke
				(width 0.1)
				(type default)
			)
			(layer "B.Fab")
		)
		(fp_line
			(start 0.67945 0.3048)
			(end 0.67945 -0.305054)
			(stroke
				(width 0.1)
				(type default)
			)
			(layer "B.Fab")
		)
		(fp_line
			(start 0.12065 0.3048)
			(end 0.67945 0.3048)
			(stroke
				(width 0.1)
				(type default)
			)
			(layer "B.Fab")
		)
		(fp_line
			(start -0.120396 0.3048)
			(end -0.120396 0.2794)
			(stroke
				(width 0.1)
				(type default)
			)
			(layer "B.Fab")
		)
		(fp_line
			(start -0.67945 0.3048)
			(end -0.120396 0.3048)
			(stroke
				(width 0.1)
				(type default)
			)
			(layer "B.Fab")
		)
		(pad "1" smd circle
			(at 0.40005 0 270)
			(size 0 0)
			(layers "B.Cu" "B.Mask" "B.Paste")
			(net "P0V9_CPU0_RT2_2A")
		)
		(pad "2" smd circle
			(at -0.40005 0 270)
			(size 0 0)
			(layers "B.Cu" "B.Mask" "B.Paste")
			(net "GND")
		)
	)
	(footprint ""
		(layer "B.Cu")
		(at 171.2849 -109.055408)
		(property "Reference" "R172"
			(at 0 0 0)
			(layer "B.SilkS")
			(hide yes)
			(effects
				(font
					(size 1.27 1.27)
				)
				(justify mirror)
			)
		)
		(property "Value" ""
			(at 0 0 0)
			(layer "B.Fab")
			(effects
				(font
					(size 1.27 1.27)
				)
				(justify mirror)
			)
		)
		(duplicate_pad_numbers_are_jumpers no)
		(fp_line
			(start -0.7874 -0.4064)
			(end -0.7874 0.4064)
			(stroke
				(width 0.1524)
				(type default)
			)
			(layer "B.SilkS")
		)
		(fp_line
			(start -0.7874 0.4064)
			(end 0.7874 0.4064)
			(stroke
				(width 0.1524)
				(type default)
			)
			(layer "B.SilkS")
		)
		(fp_line
			(start 0.7874 -0.4064)
			(end -0.7874 -0.4064)
			(stroke
				(width 0.1524)
				(type default)
			)
			(layer "B.SilkS")
		)
		(fp_line
			(start 0.7874 0.4064)
			(end 0.7874 -0.4064)
			(stroke
				(width 0.1524)
				(type default)
			)
			(layer "B.SilkS")
		)
		(fp_line
			(start -0.67945 -0.3048)
			(end -0.67945 0.3048)
			(stroke
				(width 0.1)
				(type default)
			)
			(layer "B.Fab")
		)
		(fp_line
			(start -0.67945 0.3048)
			(end -0.120396 0.3048)
			(stroke
				(width 0.1)
				(type default)
			)
			(layer "B.Fab")
		)
		(fp_line
			(start -0.12065 -0.3048)
			(end -0.67945 -0.3048)
			(stroke
				(width 0.1)
				(type default)
			)
			(layer "B.Fab")
		)
		(fp_line
			(start -0.12065 -0.2794)
			(end -0.12065 -0.3048)
			(stroke
				(width 0.1)
				(type default)
			)
			(layer "B.Fab")
		)
		(fp_line
			(start -0.120396 0.2794)
			(end 0.12065 0.2794)
			(stroke
				(width 0.1)
				(type default)
			)
			(layer "B.Fab")
		)
		(fp_line
			(start -0.120396 0.3048)
			(end -0.120396 0.2794)
			(stroke
				(width 0.1)
				(type default)
			)
			(layer "B.Fab")
		)
		(fp_line
			(start 0.12065 -0.305054)
			(end 0.12065 -0.2794)
			(stroke
				(width 0.1)
				(type default)
			)
			(layer "B.Fab")
		)
		(fp_line
			(start 0.12065 -0.2794)
			(end -0.12065 -0.2794)
			(stroke
				(width 0.1)
				(type default)
			)
			(layer "B.Fab")
		)
		(fp_line
			(start 0.12065 0.2794)
			(end 0.12065 0.3048)
			(stroke
				(width 0.1)
				(type default)
			)
			(layer "B.Fab")
		)
		(fp_line
			(start 0.12065 0.3048)
			(end 0.67945 0.3048)
			(stroke
				(width 0.1)
				(type default)
			)
			(layer "B.Fab")
		)
		(fp_line
			(start 0.67945 -0.305054)
			(end 0.12065 -0.305054)
			(stroke
				(width 0.1)
				(type default)
			)
			(layer "B.Fab")
		)
		(fp_line
			(start 0.67945 0.3048)
			(end 0.67945 -0.305054)
			(stroke
				(width 0.1)
				(type default)
			)
			(layer "B.Fab")
		)
		(pad "1" smd circle
			(at 0.40005 0 180)
			(size 0 0)
			(layers "B.Cu" "B.Mask" "B.Paste")
			(net "FM_I3C_CPU1_MUX1_R_SEL")
		)
		(pad "2" smd circle
			(at -0.40005 0 180)
			(size 0 0)
			(layers "B.Cu" "B.Mask" "B.Paste")
			(net "FM_I3C_CPU1_MUX1_SEL")
		)
	)
	(footprint ""
		(layer "B.Cu")
		(at 232.537 -333.883 -90)
		(property "Reference" "R6769"
			(at 0 0 90)
			(layer "B.SilkS")
			(hide yes)
			(effects
				(font
					(size 1.27 1.27)
				)
				(justify mirror)
			)
		)
		(property "Value" ""
			(at 0 0 90)
			(layer "B.Fab")
			(effects
				(font
					(size 1.27 1.27)
				)
				(justify mirror)
			)
		)
		(duplicate_pad_numbers_are_jumpers no)
		(fp_line
			(start -0.32512 0.175006)
			(end 0.32512 0.175006)
			(stroke
				(width 0.1)
				(type default)
			)
			(layer "B.Fab")
		)
		(fp_line
			(start 0.32512 0.175006)
			(end 0.32512 -0.175006)
			(stroke
				(width 0.1)
				(type default)
			)
			(layer "B.Fab")
		)
		(fp_line
			(start -0.32512 -0.175006)
			(end -0.32512 0.175006)
			(stroke
				(width 0.1)
				(type default)
			)
			(layer "B.Fab")
		)
		(fp_line
			(start 0.32512 -0.175006)
			(end -0.32512 -0.175006)
			(stroke
				(width 0.1)
				(type default)
			)
			(layer "B.Fab")
		)
		(pad "1" smd rect
			(at 0.2667 0 90)
			(size 0.3048 0.381)
			(layers "B.Cu" "B.Mask" "B.Paste")
			(net "P1V8_CPU0_RT_1D")
		)
		(pad "2" smd rect
			(at -0.2667 0 270)
			(size 0.3048 0.381)
			(layers "B.Cu" "B.Mask" "B.Paste")
			(net "SMB_RT_CPU0_P2_R_SCL")
		)
	)
	(footprint ""
		(layer "B.Cu")
		(at 324.916038 -395.466062 -90)
		(property "Reference" "C503"
			(at 0 0 90)
			(layer "B.SilkS")
			(hide yes)
			(effects
				(font
					(size 1.27 1.27)
				)
				(justify mirror)
			)
		)
		(property "Value" ""
			(at 0 0 90)
			(layer "B.Fab")
			(effects
				(font
					(size 1.27 1.27)
				)
				(justify mirror)
			)
		)
		(duplicate_pad_numbers_are_jumpers no)
		(fp_line
			(start -1.524 0.762)
			(end 1.524 0.762)
			(stroke
				(width 0.1524)
				(type default)
			)
			(layer "B.SilkS")
		)
		(fp_line
			(start 1.524 0.762)
			(end 1.524 -0.762)
			(stroke
				(width 0.1524)
				(type default)
			)
			(layer "B.SilkS")
		)
		(fp_line
			(start -1.524 -0.762)
			(end -1.524 0.762)
			(stroke
				(width 0.1524)
				(type default)
			)
			(layer "B.SilkS")
		)
		(fp_line
			(start 1.524 -0.762)
			(end -1.524 -0.762)
			(stroke
				(width 0.1524)
				(type default)
			)
			(layer "B.SilkS")
		)
		(fp_line
			(start -1.1049 0.724916)
			(end -1.1049 -0.724916)
			(stroke
				(width 0.1)
				(type default)
			)
			(layer "B.Fab")
		)
		(fp_line
			(start 1.1049 0.724916)
			(end -1.1049 0.724916)
			(stroke
				(width 0.1)
				(type default)
			)
			(layer "B.Fab")
		)
		(fp_line
			(start -1.1049 -0.724916)
			(end 1.1049 -0.724916)
			(stroke
				(width 0.1)
				(type default)
			)
			(layer "B.Fab")
		)
		(fp_line
			(start 1.1049 -0.724916)
			(end 1.1049 0.724916)
			(stroke
				(width 0.1)
				(type default)
			)
			(layer "B.Fab")
		)
		(pad "1" smd rect
			(at 0.889 0 270)
			(size 1.016 1.27)
			(layers "B.Cu" "B.Mask" "B.Paste")
			(net "P1V8_CPU0_RT0_1A")
		)
		(pad "2" smd rect
			(at -0.889 0 270)
			(size 1.016 1.27)
			(layers "B.Cu" "B.Mask" "B.Paste")
			(net "GND")
		)
	)
	(footprint ""
		(layer "B.Cu")
		(at 108.627164 -261.748016 90)
		(property "Reference" "C2494"
			(at 0 0 90)
			(layer "B.SilkS")
			(hide yes)
			(effects
				(font
					(size 1.27 1.27)
				)
				(justify mirror)
			)
		)
		(property "Value" ""
			(at 0 0 90)
			(layer "B.Fab")
			(effects
				(font
					(size 1.27 1.27)
				)
				(justify mirror)
			)
		)
		(duplicate_pad_numbers_are_jumpers no)
		(fp_line
			(start 0.7874 -0.4064)
			(end -0.7874 -0.4064)
			(stroke
				(width 0.1524)
				(type default)
			)
			(layer "B.SilkS")
		)
		(fp_line
			(start -0.7874 -0.4064)
			(end -0.7874 0.4064)
			(stroke
				(width 0.1524)
				(type default)
			)
			(layer "B.SilkS")
		)
		(fp_line
			(start 0.7874 0.4064)
			(end 0.7874 -0.4064)
			(stroke
				(width 0.1524)
				(type default)
			)
			(layer "B.SilkS")
		)
		(fp_line
			(start -0.7874 0.4064)
			(end 0.7874 0.4064)
			(stroke
				(width 0.1524)
				(type default)
			)
			(layer "B.SilkS")
		)
		(fp_line
			(start 0.67945 -0.305054)
			(end 0.12065 -0.305054)
			(stroke
				(width 0.1)
				(type default)
			)
			(layer "B.Fab")
		)
		(fp_line
			(start 0.12065 -0.305054)
			(end 0.12065 -0.2794)
			(stroke
				(width 0.1)
				(type default)
			)
			(layer "B.Fab")
		)
		(fp_line
			(start -0.12065 -0.3048)
			(end -0.67945 -0.3048)
			(stroke
				(width 0.1)
				(type default)
			)
			(layer "B.Fab")
		)
		(fp_line
			(start -0.67945 -0.3048)
			(end -0.67945 0.3048)
			(stroke
				(width 0.1)
				(type default)
			)
			(layer "B.Fab")
		)
		(fp_line
			(start 0.12065 -0.2794)
			(end -0.12065 -0.2794)
			(stroke
				(width 0.1)
				(type default)
			)
			(layer "B.Fab")
		)
		(fp_line
			(start -0.12065 -0.2794)
			(end -0.12065 -0.3048)
			(stroke
				(width 0.1)
				(type default)
			)
			(layer "B.Fab")
		)
		(fp_line
			(start 0.12065 0.2794)
			(end 0.12065 0.3048)
			(stroke
				(width 0.1)
				(type default)
			)
			(layer "B.Fab")
		)
		(fp_line
			(start -0.120396 0.2794)
			(end 0.12065 0.2794)
			(stroke
				(width 0.1)
				(type default)
			)
			(layer "B.Fab")
		)
		(fp_line
			(start 0.67945 0.3048)
			(end 0.67945 -0.305054)
			(stroke
				(width 0.1)
				(type default)
			)
			(layer "B.Fab")
		)
		(fp_line
			(start 0.12065 0.3048)
			(end 0.67945 0.3048)
			(stroke
				(width 0.1)
				(type default)
			)
			(layer "B.Fab")
		)
		(fp_line
			(start -0.120396 0.3048)
			(end -0.120396 0.2794)
			(stroke
				(width 0.1)
				(type default)
			)
			(layer "B.Fab")
		)
		(fp_line
			(start -0.67945 0.3048)
			(end -0.120396 0.3048)
			(stroke
				(width 0.1)
				(type default)
			)
			(layer "B.Fab")
		)
		(pad "1" smd circle
			(at 0.40005 0 270)
			(size 0 0)
			(layers "B.Cu" "B.Mask" "B.Paste")
			(net "PVDD11_S3_P1")
		)
		(pad "2" smd circle
			(at -0.40005 0 270)
			(size 0 0)
			(layers "B.Cu" "B.Mask" "B.Paste")
			(net "GND")
		)
	)
)
